(kicad_pcb
	(version 20260206)
	(generator "pcbnew")
	(generator_version "10.0")
	(general
		(thickness 1.6)
		(legacy_teardrops no)
	)
	(paper "A4")
	(title_block
		(title "04192023_DAF0TMB3IC0_F0TG_MB_C_brd_V02_OCP.brd")
		(comment 1 "Grand Teton / footprints 5070-5075 of 8354")
	)
	(layers
		(0 "F.Cu" signal "TOP")
		(4 "In1.Cu" signal "GND")
		(6 "In2.Cu" signal "IN1")
		(8 "In3.Cu" signal "GND1")
		(10 "In4.Cu" signal "IN2")
		(12 "In5.Cu" signal "GND2")
		(14 "In6.Cu" signal "IN3")
		(16 "In7.Cu" signal "GND3")
		(18 "In8.Cu" signal "VCC")
		(20 "In9.Cu" signal "VCC1")
		(22 "In10.Cu" signal "GND4")
		(24 "In11.Cu" signal "IN4")
		(26 "In12.Cu" signal "GND5")
		(28 "In13.Cu" signal "IN5")
		(30 "In14.Cu" signal "GND6")
		(32 "In15.Cu" signal "IN6")
		(34 "In16.Cu" signal "GND7")
		(2 "B.Cu" signal "BOTTOM")
		(9 "F.Adhes" user "F.Adhesive")
		(11 "B.Adhes" user "B.Adhesive")
		(13 "F.Paste" user "Package Geometry/Pastemask Top")
		(15 "B.Paste" user "Package Geometry/Pastemask Bottom")
		(5 "F.SilkS" user "Ref Des/Silkscreen Top")
		(7 "B.SilkS" user "Ref Des/Silkscreen Bottom")
		(1 "F.Mask" user "Board Geometry/Soldermask Top")
		(3 "B.Mask" user "Board Geometry/Soldermask Bottom")
		(17 "Dwgs.User" user "User.Drawings")
		(19 "Cmts.User" user "User.Comments")
		(21 "Eco1.User" user "User.Eco1")
		(23 "Eco2.User" user "User.Eco2")
		(25 "Edge.Cuts" user "Board Geometry/Outline")
		(27 "Margin" user)
		(31 "F.CrtYd" user "Package Geometry/Place Bound Top")
		(29 "B.CrtYd" user "Package Geometry/Place Bound Bottom")
		(35 "F.Fab" user "Ref Des/Assembly Top")
		(33 "B.Fab" user "Ref Des/Assembly Bottom")
	)
	(footprint ""
		(layer "B.Cu")
		(at 70.172834 -202.688952)
		(property "Reference" "R535"
			(at 0 0 0)
			(layer "B.SilkS")
			(hide yes)
			(effects
				(font
					(size 1.27 1.27)
				)
				(justify mirror)
			)
		)
		(property "Value" ""
			(at 0 0 0)
			(layer "B.Fab")
			(effects
				(font
					(size 1.27 1.27)
				)
				(justify mirror)
			)
		)
		(duplicate_pad_numbers_are_jumpers no)
		(fp_line
			(start -0.7874 -0.4064)
			(end -0.7874 0.4064)
			(stroke
				(width 0.1524)
				(type default)
			)
			(layer "B.SilkS")
		)
		(fp_line
			(start -0.7874 0.4064)
			(end 0.7874 0.4064)
			(stroke
				(width 0.1524)
				(type default)
			)
			(layer "B.SilkS")
		)
		(fp_line
			(start 0.7874 -0.4064)
			(end -0.7874 -0.4064)
			(stroke
				(width 0.1524)
				(type default)
			)
			(layer "B.SilkS")
		)
		(fp_line
			(start 0.7874 0.4064)
			(end 0.7874 -0.4064)
			(stroke
				(width 0.1524)
				(type default)
			)
			(layer "B.SilkS")
		)
		(fp_line
			(start -0.67945 -0.3048)
			(end -0.67945 0.3048)
			(stroke
				(width 0.1)
				(type default)
			)
			(layer "B.Fab")
		)
		(fp_line
			(start -0.67945 0.3048)
			(end -0.120396 0.3048)
			(stroke
				(width 0.1)
				(type default)
			)
			(layer "B.Fab")
		)
		(fp_line
			(start -0.12065 -0.3048)
			(end -0.67945 -0.3048)
			(stroke
				(width 0.1)
				(type default)
			)
			(layer "B.Fab")
		)
		(fp_line
			(start -0.12065 -0.2794)
			(end -0.12065 -0.3048)
			(stroke
				(width 0.1)
				(type default)
			)
			(layer "B.Fab")
		)
		(fp_line
			(start -0.120396 0.2794)
			(end 0.12065 0.2794)
			(stroke
				(width 0.1)
				(type default)
			)
			(layer "B.Fab")
		)
		(fp_line
			(start -0.120396 0.3048)
			(end -0.120396 0.2794)
			(stroke
				(width 0.1)
				(type default)
			)
			(layer "B.Fab")
		)
		(fp_line
			(start 0.12065 -0.305054)
			(end 0.12065 -0.2794)
			(stroke
				(width 0.1)
				(type default)
			)
			(layer "B.Fab")
		)
		(fp_line
			(start 0.12065 -0.2794)
			(end -0.12065 -0.2794)
			(stroke
				(width 0.1)
				(type default)
			)
			(layer "B.Fab")
		)
		(fp_line
			(start 0.12065 0.2794)
			(end 0.12065 0.3048)
			(stroke
				(width 0.1)
				(type default)
			)
			(layer "B.Fab")
		)
		(fp_line
			(start 0.12065 0.3048)
			(end 0.67945 0.3048)
			(stroke
				(width 0.1)
				(type default)
			)
			(layer "B.Fab")
		)
		(fp_line
			(start 0.67945 -0.305054)
			(end 0.12065 -0.305054)
			(stroke
				(width 0.1)
				(type default)
			)
			(layer "B.Fab")
		)
		(fp_line
			(start 0.67945 0.3048)
			(end 0.67945 -0.305054)
			(stroke
				(width 0.1)
				(type default)
			)
			(layer "B.Fab")
		)
		(pad "1" smd circle
			(at 0.40005 0 180)
			(size 0 0)
			(layers "B.Cu" "B.Mask" "B.Paste")
			(net "APML_CPU1_ALERT_N")
		)
		(pad "2" smd circle
			(at -0.40005 0 180)
			(size 0 0)
			(layers "B.Cu" "B.Mask" "B.Paste")
			(net "PVDD18_S5_P1")
		)
	)
	(footprint ""
		(layer "B.Cu")
		(at 65.391284 -390.560052 90)
		(property "Reference" "C269"
			(at 0 0 90)
			(layer "B.SilkS")
			(hide yes)
			(effects
				(font
					(size 1.27 1.27)
				)
				(justify mirror)
			)
		)
		(property "Value" ""
			(at 0 0 90)
			(layer "B.Fab")
			(effects
				(font
					(size 1.27 1.27)
				)
				(justify mirror)
			)
		)
		(duplicate_pad_numbers_are_jumpers no)
		(fp_line
			(start 0.7874 -0.4064)
			(end -0.7874 -0.4064)
			(stroke
				(width 0.1524)
				(type default)
			)
			(layer "B.SilkS")
		)
		(fp_line
			(start -0.7874 -0.4064)
			(end -0.7874 0.4064)
			(stroke
				(width 0.1524)
				(type default)
			)
			(layer "B.SilkS")
		)
		(fp_line
			(start 0.7874 0.4064)
			(end 0.7874 -0.4064)
			(stroke
				(width 0.1524)
				(type default)
			)
			(layer "B.SilkS")
		)
		(fp_line
			(start -0.7874 0.4064)
			(end 0.7874 0.4064)
			(stroke
				(width 0.1524)
				(type default)
			)
			(layer "B.SilkS")
		)
		(fp_line
			(start 0.67945 -0.305054)
			(end 0.12065 -0.305054)
			(stroke
				(width 0.1)
				(type default)
			)
			(layer "B.Fab")
		)
		(fp_line
			(start 0.12065 -0.305054)
			(end 0.12065 -0.2794)
			(stroke
				(width 0.1)
				(type default)
			)
			(layer "B.Fab")
		)
		(fp_line
			(start -0.12065 -0.3048)
			(end -0.67945 -0.3048)
			(stroke
				(width 0.1)
				(type default)
			)
			(layer "B.Fab")
		)
		(fp_line
			(start -0.67945 -0.3048)
			(end -0.67945 0.3048)
			(stroke
				(width 0.1)
				(type default)
			)
			(layer "B.Fab")
		)
		(fp_line
			(start 0.12065 -0.2794)
			(end -0.12065 -0.2794)
			(stroke
				(width 0.1)
				(type default)
			)
			(layer "B.Fab")
		)
		(fp_line
			(start -0.12065 -0.2794)
			(end -0.12065 -0.3048)
			(stroke
				(width 0.1)
				(type default)
			)
			(layer "B.Fab")
		)
		(fp_line
			(start 0.12065 0.2794)
			(end 0.12065 0.3048)
			(stroke
				(width 0.1)
				(type default)
			)
			(layer "B.Fab")
		)
		(fp_line
			(start -0.120396 0.2794)
			(end 0.12065 0.2794)
			(stroke
				(width 0.1)
				(type default)
			)
			(layer "B.Fab")
		)
		(fp_line
			(start 0.67945 0.3048)
			(end 0.67945 -0.305054)
			(stroke
				(width 0.1)
				(type default)
			)
			(layer "B.Fab")
		)
		(fp_line
			(start 0.12065 0.3048)
			(end 0.67945 0.3048)
			(stroke
				(width 0.1)
				(type default)
			)
			(layer "B.Fab")
		)
		(fp_line
			(start -0.120396 0.3048)
			(end -0.120396 0.2794)
			(stroke
				(width 0.1)
				(type default)
			)
			(layer "B.Fab")
		)
		(fp_line
			(start -0.67945 0.3048)
			(end -0.120396 0.3048)
			(stroke
				(width 0.1)
				(type default)
			)
			(layer "B.Fab")
		)
		(pad "1" smd circle
			(at 0.40005 0 270)
			(size 0 0)
			(layers "B.Cu" "B.Mask" "B.Paste")
			(net "P0V9_CPU1_RT0_2A")
		)
		(pad "2" smd circle
			(at -0.40005 0 270)
			(size 0 0)
			(layers "B.Cu" "B.Mask" "B.Paste")
			(net "GND")
		)
	)
	(footprint ""
		(layer "B.Cu")
		(at 109.895386 -250.257564)
		(property "Reference" "C2322"
			(at 0 0 0)
			(layer "B.SilkS")
			(hide yes)
			(effects
				(font
					(size 1.27 1.27)
				)
				(justify mirror)
			)
		)
		(property "Value" ""
			(at 0 0 0)
			(layer "B.Fab")
			(effects
				(font
					(size 1.27 1.27)
				)
				(justify mirror)
			)
		)
		(duplicate_pad_numbers_are_jumpers no)
		(fp_line
			(start -0.7874 -0.4064)
			(end -0.7874 0.4064)
			(stroke
				(width 0.1524)
				(type default)
			)
			(layer "B.SilkS")
		)
		(fp_line
			(start -0.7874 0.4064)
			(end 0.7874 0.4064)
			(stroke
				(width 0.1524)
				(type default)
			)
			(layer "B.SilkS")
		)
		(fp_line
			(start 0.7874 -0.4064)
			(end -0.7874 -0.4064)
			(stroke
				(width 0.1524)
				(type default)
			)
			(layer "B.SilkS")
		)
		(fp_line
			(start 0.7874 0.4064)
			(end 0.7874 -0.4064)
			(stroke
				(width 0.1524)
				(type default)
			)
			(layer "B.SilkS")
		)
		(fp_line
			(start -0.67945 -0.3048)
			(end -0.67945 0.3048)
			(stroke
				(width 0.1)
				(type default)
			)
			(layer "B.Fab")
		)
		(fp_line
			(start -0.67945 0.3048)
			(end -0.120396 0.3048)
			(stroke
				(width 0.1)
				(type default)
			)
			(layer "B.Fab")
		)
		(fp_line
			(start -0.12065 -0.3048)
			(end -0.67945 -0.3048)
			(stroke
				(width 0.1)
				(type default)
			)
			(layer "B.Fab")
		)
		(fp_line
			(start -0.12065 -0.2794)
			(end -0.12065 -0.3048)
			(stroke
				(width 0.1)
				(type default)
			)
			(layer "B.Fab")
		)
		(fp_line
			(start -0.120396 0.2794)
			(end 0.12065 0.2794)
			(stroke
				(width 0.1)
				(type default)
			)
			(layer "B.Fab")
		)
		(fp_line
			(start -0.120396 0.3048)
			(end -0.120396 0.2794)
			(stroke
				(width 0.1)
				(type default)
			)
			(layer "B.Fab")
		)
		(fp_line
			(start 0.12065 -0.305054)
			(end 0.12065 -0.2794)
			(stroke
				(width 0.1)
				(type default)
			)
			(layer "B.Fab")
		)
		(fp_line
			(start 0.12065 -0.2794)
			(end -0.12065 -0.2794)
			(stroke
				(width 0.1)
				(type default)
			)
			(layer "B.Fab")
		)
		(fp_line
			(start 0.12065 0.2794)
			(end 0.12065 0.3048)
			(stroke
				(width 0.1)
				(type default)
			)
			(layer "B.Fab")
		)
		(fp_line
			(start 0.12065 0.3048)
			(end 0.67945 0.3048)
			(stroke
				(width 0.1)
				(type default)
			)
			(layer "B.Fab")
		)
		(fp_line
			(start 0.67945 -0.305054)
			(end 0.12065 -0.305054)
			(stroke
				(width 0.1)
				(type default)
			)
			(layer "B.Fab")
		)
		(fp_line
			(start 0.67945 0.3048)
			(end 0.67945 -0.305054)
			(stroke
				(width 0.1)
				(type default)
			)
			(layer "B.Fab")
		)
		(pad "1" smd circle
			(at 0.40005 0 180)
			(size 0 0)
			(layers "B.Cu" "B.Mask" "B.Paste")
			(net "PVDDCR_CPU0_P1")
		)
		(pad "2" smd circle
			(at -0.40005 0 180)
			(size 0 0)
			(layers "B.Cu" "B.Mask" "B.Paste")
			(net "GND")
		)
	)
	(footprint ""
		(layer "B.Cu")
		(at 115.275868 -256.012442 -90)
		(property "Reference" "C2418"
			(at 0 0 90)
			(layer "B.SilkS")
			(hide yes)
			(effects
				(font
					(size 1.27 1.27)
				)
				(justify mirror)
			)
		)
		(property "Value" ""
			(at 0 0 90)
			(layer "B.Fab")
			(effects
				(font
					(size 1.27 1.27)
				)
				(justify mirror)
			)
		)
		(duplicate_pad_numbers_are_jumpers no)
		(fp_line
			(start -0.7874 0.4064)
			(end 0.7874 0.4064)
			(stroke
				(width 0.1524)
				(type default)
			)
			(layer "B.SilkS")
		)
		(fp_line
			(start 0.7874 0.4064)
			(end 0.7874 -0.4064)
			(stroke
				(width 0.1524)
				(type default)
			)
			(layer "B.SilkS")
		)
		(fp_line
			(start -0.7874 -0.4064)
			(end -0.7874 0.4064)
			(stroke
				(width 0.1524)
				(type default)
			)
			(layer "B.SilkS")
		)
		(fp_line
			(start 0.7874 -0.4064)
			(end -0.7874 -0.4064)
			(stroke
				(width 0.1524)
				(type default)
			)
			(layer "B.SilkS")
		)
		(fp_line
			(start -0.67945 0.3048)
			(end -0.120396 0.3048)
			(stroke
				(width 0.1)
				(type default)
			)
			(layer "B.Fab")
		)
		(fp_line
			(start -0.120396 0.3048)
			(end -0.120396 0.2794)
			(stroke
				(width 0.1)
				(type default)
			)
			(layer "B.Fab")
		)
		(fp_line
			(start 0.12065 0.3048)
			(end 0.67945 0.3048)
			(stroke
				(width 0.1)
				(type default)
			)
			(layer "B.Fab")
		)
		(fp_line
			(start 0.67945 0.3048)
			(end 0.67945 -0.305054)
			(stroke
				(width 0.1)
				(type default)
			)
			(layer "B.Fab")
		)
		(fp_line
			(start -0.120396 0.2794)
			(end 0.12065 0.2794)
			(stroke
				(width 0.1)
				(type default)
			)
			(layer "B.Fab")
		)
		(fp_line
			(start 0.12065 0.2794)
			(end 0.12065 0.3048)
			(stroke
				(width 0.1)
				(type default)
			)
			(layer "B.Fab")
		)
		(fp_line
			(start -0.12065 -0.2794)
			(end -0.12065 -0.3048)
			(stroke
				(width 0.1)
				(type default)
			)
			(layer "B.Fab")
		)
		(fp_line
			(start 0.12065 -0.2794)
			(end -0.12065 -0.2794)
			(stroke
				(width 0.1)
				(type default)
			)
			(layer "B.Fab")
		)
		(fp_line
			(start -0.67945 -0.3048)
			(end -0.67945 0.3048)
			(stroke
				(width 0.1)
				(type default)
			)
			(layer "B.Fab")
		)
		(fp_line
			(start -0.12065 -0.3048)
			(end -0.67945 -0.3048)
			(stroke
				(width 0.1)
				(type default)
			)
			(layer "B.Fab")
		)
		(fp_line
			(start 0.12065 -0.305054)
			(end 0.12065 -0.2794)
			(stroke
				(width 0.1)
				(type default)
			)
			(layer "B.Fab")
		)
		(fp_line
			(start 0.67945 -0.305054)
			(end 0.12065 -0.305054)
			(stroke
				(width 0.1)
				(type default)
			)
			(layer "B.Fab")
		)
		(pad "1" smd circle
			(at 0.40005 0 90)
			(size 0 0)
			(layers "B.Cu" "B.Mask" "B.Paste")
			(net "PVDDCR_SOC_P1")
		)
		(pad "2" smd circle
			(at -0.40005 0 90)
			(size 0 0)
			(layers "B.Cu" "B.Mask" "B.Paste")
			(net "GND")
		)
	)
	(footprint ""
		(layer "B.Cu")
		(at 363.804454 -266.00531)
		(property "Reference" "C2656"
			(at 0 0 0)
			(layer "B.SilkS")
			(hide yes)
			(effects
				(font
					(size 1.27 1.27)
				)
				(justify mirror)
			)
		)
		(property "Value" ""
			(at 0 0 0)
			(layer "B.Fab")
			(effects
				(font
					(size 1.27 1.27)
				)
				(justify mirror)
			)
		)
		(duplicate_pad_numbers_are_jumpers no)
		(fp_line
			(start -0.7874 -0.4064)
			(end -0.7874 0.4064)
			(stroke
				(width 0.1524)
				(type default)
			)
			(layer "B.SilkS")
		)
		(fp_line
			(start -0.7874 0.4064)
			(end 0.7874 0.4064)
			(stroke
				(width 0.1524)
				(type default)
			)
			(layer "B.SilkS")
		)
		(fp_line
			(start 0.7874 -0.4064)
			(end -0.7874 -0.4064)
			(stroke
				(width 0.1524)
				(type default)
			)
			(layer "B.SilkS")
		)
		(fp_line
			(start 0.7874 0.4064)
			(end 0.7874 -0.4064)
			(stroke
				(width 0.1524)
				(type default)
			)
			(layer "B.SilkS")
		)
		(fp_line
			(start -0.67945 -0.3048)
			(end -0.67945 0.3048)
			(stroke
				(width 0.1)
				(type default)
			)
			(layer "B.Fab")
		)
		(fp_line
			(start -0.67945 0.3048)
			(end -0.120396 0.3048)
			(stroke
				(width 0.1)
				(type default)
			)
			(layer "B.Fab")
		)
		(fp_line
			(start -0.12065 -0.3048)
			(end -0.67945 -0.3048)
			(stroke
				(width 0.1)
				(type default)
			)
			(layer "B.Fab")
		)
		(fp_line
			(start -0.12065 -0.2794)
			(end -0.12065 -0.3048)
			(stroke
				(width 0.1)
				(type default)
			)
			(layer "B.Fab")
		)
		(fp_line
			(start -0.120396 0.2794)
			(end 0.12065 0.2794)
			(stroke
				(width 0.1)
				(type default)
			)
			(layer "B.Fab")
		)
		(fp_line
			(start -0.120396 0.3048)
			(end -0.120396 0.2794)
			(stroke
				(width 0.1)
				(type default)
			)
			(layer "B.Fab")
		)
		(fp_line
			(start 0.12065 -0.305054)
			(end 0.12065 -0.2794)
			(stroke
				(width 0.1)
				(type default)
			)
			(layer "B.Fab")
		)
		(fp_line
			(start 0.12065 -0.2794)
			(end -0.12065 -0.2794)
			(stroke
				(width 0.1)
				(type default)
			)
			(layer "B.Fab")
		)
		(fp_line
			(start 0.12065 0.2794)
			(end 0.12065 0.3048)
			(stroke
				(width 0.1)
				(type default)
			)
			(layer "B.Fab")
		)
		(fp_line
			(start 0.12065 0.3048)
			(end 0.67945 0.3048)
			(stroke
				(width 0.1)
				(type default)
			)
			(layer "B.Fab")
		)
		(fp_line
			(start 0.67945 -0.305054)
			(end 0.12065 -0.305054)
			(stroke
				(width 0.1)
				(type default)
			)
			(layer "B.Fab")
		)
		(fp_line
			(start 0.67945 0.3048)
			(end 0.67945 -0.305054)
			(stroke
				(width 0.1)
				(type default)
			)
			(layer "B.Fab")
		)
		(pad "1" smd circle
			(at 0.40005 0 180)
			(size 0 0)
			(layers "B.Cu" "B.Mask" "B.Paste")
			(net "PVDD11_S3_P0")
		)
		(pad "2" smd circle
			(at -0.40005 0 180)
			(size 0 0)
			(layers "B.Cu" "B.Mask" "B.Paste")
			(net "GND")
		)
	)
	(footprint ""
		(layer "B.Cu")
		(at 365.835692 -256.505202)
		(property "Reference" "C2147"
			(at 0 0 0)
			(layer "B.SilkS")
			(hide yes)
			(effects
				(font
					(size 1.27 1.27)
				)
				(justify mirror)
			)
		)
		(property "Value" ""
			(at 0 0 0)
			(layer "B.Fab")
			(effects
				(font
					(size 1.27 1.27)
				)
				(justify mirror)
			)
		)
		(duplicate_pad_numbers_are_jumpers no)
		(fp_line
			(start -0.7874 -0.4064)
			(end -0.7874 0.4064)
			(stroke
				(width 0.1524)
				(type default)
			)
			(layer "B.SilkS")
		)
		(fp_line
			(start -0.7874 0.4064)
			(end 0.7874 0.4064)
			(stroke
				(width 0.1524)
				(type default)
			)
			(layer "B.SilkS")
		)
		(fp_line
			(start 0.7874 -0.4064)
			(end -0.7874 -0.4064)
			(stroke
				(width 0.1524)
				(type default)
			)
			(layer "B.SilkS")
		)
		(fp_line
			(start 0.7874 0.4064)
			(end 0.7874 -0.4064)
			(stroke
				(width 0.1524)
				(type default)
			)
			(layer "B.SilkS")
		)
		(fp_line
			(start -0.67945 -0.3048)
			(end -0.67945 0.3048)
			(stroke
				(width 0.1)
				(type default)
			)
			(layer "B.Fab")
		)
		(fp_line
			(start -0.67945 0.3048)
			(end -0.120396 0.3048)
			(stroke
				(width 0.1)
				(type default)
			)
			(layer "B.Fab")
		)
		(fp_line
			(start -0.12065 -0.3048)
			(end -0.67945 -0.3048)
			(stroke
				(width 0.1)
				(type default)
			)
			(layer "B.Fab")
		)
		(fp_line
			(start -0.12065 -0.2794)
			(end -0.12065 -0.3048)
			(stroke
				(width 0.1)
				(type default)
			)
			(layer "B.Fab")
		)
		(fp_line
			(start -0.120396 0.2794)
			(end 0.12065 0.2794)
			(stroke
				(width 0.1)
				(type default)
			)
			(layer "B.Fab")
		)
		(fp_line
			(start -0.120396 0.3048)
			(end -0.120396 0.2794)
			(stroke
				(width 0.1)
				(type default)
			)
			(layer "B.Fab")
		)
		(fp_line
			(start 0.12065 -0.305054)
			(end 0.12065 -0.2794)
			(stroke
				(width 0.1)
				(type default)
			)
			(layer "B.Fab")
		)
		(fp_line
			(start 0.12065 -0.2794)
			(end -0.12065 -0.2794)
			(stroke
				(width 0.1)
				(type default)
			)
			(layer "B.Fab")
		)
		(fp_line
			(start 0.12065 0.2794)
			(end 0.12065 0.3048)
			(stroke
				(width 0.1)
				(type default)
			)
			(layer "B.Fab")
		)
		(fp_line
			(start 0.12065 0.3048)
			(end 0.67945 0.3048)
			(stroke
				(width 0.1)
				(type default)
			)
			(layer "B.Fab")
		)
		(fp_line
			(start 0.67945 -0.305054)
			(end 0.12065 -0.305054)
			(stroke
				(width 0.1)
				(type default)
			)
			(layer "B.Fab")
		)
		(fp_line
			(start 0.67945 0.3048)
			(end 0.67945 -0.305054)
			(stroke
				(width 0.1)
				(type default)
			)
			(layer "B.Fab")
		)
		(pad "1" smd circle
			(at 0.40005 0 180)
			(size 0 0)
			(layers "B.Cu" "B.Mask" "B.Paste")
			(net "PVDDCR_SOC_P0")
		)
		(pad "2" smd circle
			(at -0.40005 0 180)
			(size 0 0)
			(layers "B.Cu" "B.Mask" "B.Paste")
			(net "GND")
		)
	)
)
